# BASEBOARD_FAB2 (Tioga Pass) — schematic netlist excerpt (pin names and nets, part order shuffled) for the footprints in the layout excerpt that follows; sources: Cadence DE-HDL packaged netlist, KiCad conversion of Wiwynn_Tioga_Pass_MB.brd

L1B1  IND-100NH-35-GP  pkg DISCRET-G8  page 228 : S = P12V_STBY ; F = VR_FET_SW_P12V_STBY_PVDDQ_KLM
RT37  RES  0 5.0% CHIP  pkg 0603  page 210 : A = VR_PVSA_CPU1_BOOT ; B = VR_PVSA_CPU1_BOOT_R
C1C17  CAP_A  0.1UF 16V 10% X7R  pkg 0402V  page 210 : A = VR_FET_SW_P12V_STBY_PVCCIN_CPU1 ; B = GND

(kicad_pcb
	(version 20260206)
	(generator "pcbnew")
	(generator_version "10.0")
	(general
		(thickness 1.6)
		(legacy_teardrops no)
	)
	(paper "A4")
	(title_block
		(title "Wiwynn_Tioga_Pass_MB.brd")
		(comment 1 "Tioga Pass / footprints 1791-1793 of 4770")
	)
	(layers
		(0 "F.Cu" signal "TOP")
		(4 "In1.Cu" signal "L2GND")
		(6 "In2.Cu" signal "L3")
		(8 "In3.Cu" signal "L4GND")
		(10 "In4.Cu" signal "L5")
		(12 "In5.Cu" signal "L6GND")
		(14 "In6.Cu" signal "L7VCC")
		(16 "In7.Cu" signal "L8VCC")
		(18 "In8.Cu" signal "L9GND")
		(20 "In9.Cu" signal "L10")
		(22 "In10.Cu" signal "L11GND")
		(24 "In11.Cu" signal "L12")
		(26 "In12.Cu" signal "L13GND")
		(2 "B.Cu" signal "BOTTOM")
		(9 "F.Adhes" user "F.Adhesive")
		(11 "B.Adhes" user "B.Adhesive")
		(13 "F.Paste" user "Package Geometry/Pastemask Top")
		(15 "B.Paste" user "Package Geometry/Pastemask Bottom")
		(5 "F.SilkS" user "Ref Des/Silkscreen Top")
		(7 "B.SilkS" user "Ref Des/Silkscreen Bottom")
		(1 "F.Mask" user "Board Geometry/Soldermask Top")
		(3 "B.Mask" user "Board Geometry/Soldermask Bottom")
		(17 "Dwgs.User" user "User.Drawings")
		(19 "Cmts.User" user "User.Comments")
		(21 "Eco1.User" user "User.Eco1")
		(23 "Eco2.User" user "User.Eco2")
		(25 "Edge.Cuts" user "Board Geometry/Outline")
		(27 "Margin" user)
		(31 "F.CrtYd" user "Package Geometry/Place Bound Top")
		(29 "B.CrtYd" user "Package Geometry/Place Bound Bottom")
		(35 "F.Fab" user "Ref Des/Assembly Top")
		(33 "B.Fab" user "Ref Des/Assembly Bottom")
	)
	(footprint ""
		(layer "F.Cu")
		(at 28.09748 -98.59772 90)
		(property "Reference" "RT37"
			(at 1.01473 0.656336 0)
			(unlocked yes)
			(layer "F.SilkS")
			(effects
				(font
					(size 0.4064 0.254)
					(thickness 0.1524)
				)
			)
		)
		(property "Value" ""
			(at 0 0 90)
			(layer "F.Fab")
			(effects
				(font
					(size 1.27 1.27)
				)
			)
		)
		(duplicate_pad_numbers_are_jumpers no)
		(fp_poly
			(pts
				(xy -0.4953 -0.2032) (xy 0.4953 -0.2032) (xy 0.4953 1.6002) (xy -0.4953 1.6002)
			)
			(stroke
				(width 0)
				(type default)
			)
			(fill no)
			(layer "F.CrtYd")
		)
		(fp_line
			(start 0.4953 -0.2032)
			(end 0.4953 1.6002)
			(stroke
				(width 0.1)
				(type default)
			)
			(layer "F.Fab")
		)
		(fp_line
			(start -0.4953 -0.2032)
			(end 0.4953 -0.2032)
			(stroke
				(width 0.1)
				(type default)
			)
			(layer "F.Fab")
		)
		(fp_line
			(start 0.4953 1.6002)
			(end -0.4953 1.6002)
			(stroke
				(width 0.1)
				(type default)
			)
			(layer "F.Fab")
		)
		(fp_line
			(start -0.4953 1.6002)
			(end -0.4953 -0.2032)
			(stroke
				(width 0.1)
				(type default)
			)
			(layer "F.Fab")
		)
		(pad "1" smd rect
			(at 0 0 90)
			(size 0.762 0.889)
			(layers "F.Cu" "F.Mask" "F.Paste")
			(net "VR_PVSA_CPU1_BOOT")
		)
		(pad "2" smd rect
			(at 0 1.397 90)
			(size 0.762 0.889)
			(layers "F.Cu" "F.Mask" "F.Paste")
			(net "VR_PVSA_CPU1_BOOT_R")
		)
		(zone
			(layer "F.Cu")
			(hatch none 0.5)
			(connect_pads
				(clearance 0)
			)
			(min_thickness 0.25)
			(keepout
				(tracks allowed)
				(vias not_allowed)
				(pads allowed)
				(copperpour not_allowed)
				(footprints allowed)
			)
			(placement
				(enabled no)
				(sheetname "")
			)
			(fill
				(thermal_gap 0.5)
				(thermal_bridge_width 0.5)
				(island_removal_mode 0)
			)
			(polygon
				(pts
					(xy 29.04998 -98.97872) (xy 28.54198 -98.97872) (xy 28.54198 -98.21672) (xy 29.04998 -98.21672)
				)
			)
		)
		(zone
			(layer "F.Cu")
			(hatch none 0.5)
			(connect_pads
				(clearance 0)
			)
			(min_thickness 0.25)
			(keepout
				(tracks not_allowed)
				(vias allowed)
				(pads allowed)
				(copperpour not_allowed)
				(footprints allowed)
			)
			(placement
				(enabled no)
				(sheetname "")
			)
			(fill
				(thermal_gap 0.5)
				(thermal_bridge_width 0.5)
				(island_removal_mode 0)
			)
			(polygon
				(pts
					(xy 29.04998 -98.21672) (xy 29.04998 -98.97872) (xy 28.54198 -98.97872) (xy 28.54198 -98.21672)
				)
			)
		)
	)
	(footprint ""
		(layer "F.Cu")
		(at 10.414 -131.826 90)
		(property "Reference" "L1B1"
			(at 0 0 90)
			(layer "F.SilkS")
			(hide yes)
			(effects
				(font
					(size 1.27 1.27)
				)
			)
		)
		(property "Value" "*"
			(at -3.5941 0.3429 90)
			(unlocked yes)
			(layer "F.Fab")
			(hide yes)
			(effects
				(font
					(size 1.27 1.016)
					(thickness 0.1524)
				)
			)
		)
		(property "Device Type" "IND-100NH-35-GP_DISCRET-G8-INDA"
			(at -3.5941 -1.1811 90)
			(unlocked yes)
			(layer "F.Fab")
			(hide yes)
			(effects
				(font
					(size 1.27 1.016)
					(thickness 0.1524)
				)
			)
		)
		(duplicate_pad_numbers_are_jumpers no)
		(fp_line
			(start 2.2479 -2.794)
			(end 2.2479 2.794)
			(stroke
				(width 0.1524)
				(type default)
			)
			(layer "F.SilkS")
		)
		(fp_line
			(start -2.2479 -2.794)
			(end 2.2479 -2.794)
			(stroke
				(width 0.1524)
				(type default)
			)
			(layer "F.SilkS")
		)
		(fp_line
			(start 2.2479 2.794)
			(end -2.2479 2.794)
			(stroke
				(width 0.1524)
				(type default)
			)
			(layer "F.SilkS")
		)
		(fp_line
			(start -2.2479 2.794)
			(end -2.2479 -2.794)
			(stroke
				(width 0.1524)
				(type default)
			)
			(layer "F.SilkS")
		)
		(fp_rect
			(start -1.9939 1.9939)
			(end 1.9939 -1.9939)
			(stroke
				(width 0)
				(type default)
			)
			(fill no)
			(layer "F.CrtYd")
		)
		(fp_poly
			(pts
				(xy -2.5019 2.8702) (xy -2.5019 1.9939) (xy 1.9939 1.9939) (xy 1.9939 -1.9939) (xy -1.9939 -1.9939)
				(xy -1.9939 1.9812) (xy -2.5019 1.9812) (xy -2.5019 -2.8702) (xy 2.5019 -2.8702) (xy 2.5019 2.8702)
			)
			(stroke
				(width 0)
				(type default)
			)
			(fill no)
			(layer "F.CrtYd")
		)
		(fp_rect
			(start -2.5019 2.8702)
			(end 2.5019 -2.8702)
			(stroke
				(width 0)
				(type default)
			)
			(fill no)
			(layer "F.Fab")
		)
		(pad "1" smd rect
			(at 0 -1.745996 90)
			(size 1.5494 1.6002)
			(layers "F.Cu" "F.Mask" "F.Paste")
			(net "P12V_STBY")
		)
		(pad "2" smd rect
			(at 0 1.745996 90)
			(size 1.5494 1.6002)
			(layers "F.Cu" "F.Mask" "F.Paste")
			(net "VR_FET_SW_P12V_STBY_PVDDQ_KLM")
		)
	)
	(footprint ""
		(layer "F.Cu")
		(at 32.672274 -101.472492 90)
		(property "Reference" "C1C17"
			(at 0 0 90)
			(layer "F.SilkS")
			(hide yes)
			(effects
				(font
					(size 1.27 1.27)
				)
			)
		)
		(property "Value" ""
			(at 0 0 90)
			(layer "F.Fab")
			(effects
				(font
					(size 1.27 1.27)
				)
			)
		)
		(duplicate_pad_numbers_are_jumpers no)
		(fp_rect
			(start 0.3048 0.9906)
			(end -0.3048 -0.1016)
			(stroke
				(width 0)
				(type default)
			)
			(fill no)
			(layer "F.CrtYd")
		)
		(fp_line
			(start 0.3048 -0.1016)
			(end -0.3048 -0.1016)
			(stroke
				(width 0.1)
				(type default)
			)
			(layer "F.Fab")
		)
		(fp_line
			(start -0.3048 -0.1016)
			(end -0.3048 0.9906)
			(stroke
				(width 0.1)
				(type default)
			)
			(layer "F.Fab")
		)
		(fp_line
			(start 0.3048 0.9906)
			(end 0.3048 -0.1016)
			(stroke
				(width 0.1)
				(type default)
			)
			(layer "F.Fab")
		)
		(fp_line
			(start -0.3048 0.9906)
			(end 0.3048 0.9906)
			(stroke
				(width 0.1)
				(type default)
			)
			(layer "F.Fab")
		)
		(pad "1" smd rect
			(at 0 0 90)
			(size 0.508 0.508)
			(layers "F.Cu" "F.Mask" "F.Paste")
			(net "VR_FET_SW_P12V_STBY_PVCCIN_CPU1")
		)
		(pad "2" smd rect
			(at 0 0.889 90)
			(size 0.508 0.508)
			(layers "F.Cu" "F.Mask" "F.Paste")
			(net "GND")
		)
		(zone
			(layer "F.Cu")
			(hatch none 0.5)
			(connect_pads
				(clearance 0)
			)
			(min_thickness 0.25)
			(keepout
				(tracks allowed)
				(vias not_allowed)
				(pads allowed)
				(copperpour not_allowed)
				(footprints allowed)
			)
			(placement
				(enabled no)
				(sheetname "")
			)
			(fill
				(thermal_gap 0.5)
				(thermal_bridge_width 0.5)
				(island_removal_mode 0)
			)
			(polygon
				(pts
					(xy 33.307274 -101.726492) (xy 32.926274 -101.726492) (xy 32.926274 -101.218492) (xy 33.307274 -101.218492)
				)
			)
		)
		(zone
			(layer "F.Cu")
			(hatch none 0.5)
			(connect_pads
				(clearance 0)
			)
			(min_thickness 0.25)
			(keepout
				(tracks not_allowed)
				(vias allowed)
				(pads allowed)
				(copperpour not_allowed)
				(footprints allowed)
			)
			(placement
				(enabled no)
				(sheetname "")
			)
			(fill
				(thermal_gap 0.5)
				(thermal_bridge_width 0.5)
				(island_removal_mode 0)
			)
			(polygon
				(pts
					(xy 33.307274 -101.726492) (xy 32.926274 -101.726492) (xy 32.926274 -101.218492) (xy 33.307274 -101.218492)
				)
			)
		)
	)
)
